# BASEBOARD_FAB2 (Tioga Pass) — schematic netlist excerpt (pin names and nets, part order shuffled) for the footprints in the layout excerpt that follows; sources: Cadence DE-HDL packaged netlist, KiCad conversion of Wiwynn_Tioga_Pass_MB.brd

J1G3  SCONN288_H44441004  SCONN  pkg PIP  page 81
  \12v\(1)  = P12V_NVDIMM_GHJ
  VSS(93)  = GND
  DQ(4)  = M_J_DQ<5>
  VSS(92)  = GND
  DQ(0)  = M_J_DQ<1>
  VSS(91)  = GND
  DQS9P  = M_J_DQS_DP<9>
  DQS9N  = M_J_DQS_DN<9>
  VSS(90)  = GND
  DQ(6)  = M_J_DQ<7>
  VSS(89)  = GND
  DQ(2)  = M_J_DQ<3>
  VSS(88)  = GND
  DQ(12)  = M_J_DQ<13>
  VSS(87)  = GND
  DQ(8)  = M_J_DQ<9>
  VSS(86)  = GND
  DQS10P  = M_J_DQS_DP<10>
  DQS10N  = M_J_DQS_DN<10>
  VSS(85)  = GND
  DQ(14)  = M_J_DQ<15>
  VSS(84)  = GND
  DQ(10)  = M_J_DQ<11>
  VSS(83)  = GND
  DQ(20)  = M_J_DQ<21>
  VSS(82)  = GND
  DQ(16)  = M_J_DQ<17>
  VSS(81)  = GND
  DQS11P  = M_J_DQS_DP<11>
  DQS11N  = M_J_DQS_DN<11>
  VSS(80)  = GND
  DQ(22)  = M_J_DQ<23>
  VSS(79)  = GND
  DQ(18)  = M_J_DQ<19>
  VSS(78)  = GND
  DQ(28)  = M_J_DQ<29>
  VSS(77)  = GND
  DQ(24)  = M_J_DQ<25>
  VSS(76)  = GND
  DQS12P  = M_J_DQS_DP<12>
  DQS12N  = M_J_DQS_DN<12>
  VSS(75)  = GND
  DQ(30)  = M_J_DQ<31>
  VSS(74)  = GND
  DQ(26)  = M_J_DQ<27>
  VSS(73)  = GND
  CB(4)  = M_J_ECC<5>
  VSS(72)  = GND
  CB(0)  = M_J_ECC<1>
  VSS(71)  = GND
  DQS17P  = M_J_DQS_DP<17>
  DQS17N  = M_J_DQS_DN<17>
  VSS(70)  = GND
  CB(6)  = M_J_ECC<7>
  VSS(69)  = GND
  CB(2)  = M_J_ECC<3>
  VSS(68)  = GND
  RESET_N  = M_GHJ_RST_N
  VDD(25)  = PVDDQ_GHJ
  CKE(0)  = M_J_CKE<0>
  VDD(24)  = PVDDQ_GHJ
  ACT_N  = M_J_ACT_N
  BG(0)  = M_J_BG<0>
  VDD(23)  = PVDDQ_GHJ
  A12  = M_J_MA<12>
  A9  = M_J_MA<9>
  VDD(22)  = PVDDQ_GHJ
  A8  = M_J_MA<8>
  A6  = M_J_MA<6>
  VDD(21)  = PVDDQ_GHJ
  A3  = M_J_MA<3>
  A1  = M_J_MA<1>
  VDD(20)  = PVDDQ_GHJ
  CK0P  = M_J_CLK_DP<0>
  CK0N  = M_J_CLK_DN<0>
  VDD(19)  = PVDDQ_GHJ
  VTT(1)  = PVTT_GHJ
  EVENT_N  = FM_DIMM_EVENT_COD_N
  A0  = M_J_MA<0>
  VDD(18)  = PVDDQ_GHJ
  BA(0)  = M_J_BA<0>
  A16_RAS_N  = M_J_MA<16>
  VDD(17)  = PVDDQ_GHJ
  S0_N  = M_J_CS_N<0>
  VDD(16)  = PVDDQ_GHJ
  A15_CAS_N  = M_J_MA<15>
  ODT(0)  = M_J_ODT<0>
  VDD(15)  = PVDDQ_GHJ
  S1_N  = M_J_CS_N<1>
  VDD(14)  = PVDDQ_GHJ
  ODT(1)  = M_J_ODT<1>
  VDD(13)  = PVDDQ_GHJ
  S2_N_C(0)  = M_J_CS_N<2>
  VSS(67)  = GND
  DQ(36)  = M_J_DQ<37>
  VSS(66)  = GND
  DQ(32)  = M_J_DQ<33>
  VSS(65)  = GND
  DQS13P  = M_J_DQS_DP<13>
  DQS13N  = M_J_DQS_DN<13>
  VSS(64)  = GND
  DQ(38)  = M_J_DQ<39>
  VSS(63)  = GND
  DQ(34)  = M_J_DQ<35>
  VSS(62)  = GND
  DQ(44)  = M_J_DQ<45>
  VSS(61)  = GND
  DQ(40)  = M_J_DQ<41>
  VSS(60)  = GND
  DQS14P  = M_J_DQS_DP<14>
  DQS14N  = M_J_DQS_DN<14>
  VSS(59)  = GND
  DQ(46)  = M_J_DQ<47>
  VSS(58)  = GND
  DQ(42)  = M_J_DQ<43>
  VSS(57)  = GND
  DQ(52)  = M_J_DQ<53>
  VSS(56)  = GND
  DQ(48)  = M_J_DQ<49>
  VSS(55)  = GND
  DQS15P  = M_J_DQS_DP<15>
  DQS15N  = M_J_DQS_DN<15>
  VSS(54)  = GND
  DQ(54)  = M_J_DQ<55>
  VSS(53)  = GND
  DQ(50)  = M_J_DQ<51>
  VSS(52)  = GND
  DQ(60)  = M_J_DQ<61>
  VSS(51)  = GND
  DQ(56)  = M_J_DQ<57>
  VSS(50)  = GND
  DQS16P  = M_J_DQS_DP<16>
  DQS16N  = M_J_DQS_DN<16>
  VSS(49)  = GND
  DQ(62)  = M_J_DQ<63>
  VSS(48)  = GND
  DQ(58)  = M_J_DQ<59>
  VSS(47)  = GND
  SA(0)  = GND
  SA(1)  = GND
  SCL  = SMB_DDR_GHJ_VPP_SCL
  VPP(4)  = PVPP_GHJ
  VPP(3)  = PVPP_GHJ
  RFU(2)  = TP_CH_J_DIMM_J0_RFU_2
  \12v\(0)  = P12V_NVDIMM_GHJ
  VREFCA  = M_J_VREF
  VSS(46)  = GND
  DQ(5)  = M_J_DQ<4>
  VSS(45)  = GND
  DQ(1)  = M_J_DQ<0>
  VSS(44)  = GND
  DQS0N  = M_J_DQS_DN<0>
  DQS0P  = M_J_DQS_DP<0>
  VSS(43)  = GND
  DQ(7)  = M_J_DQ<6>
  VSS(42)  = GND
  DQ(3)  = M_J_DQ<2>
  VSS(41)  = GND
  DQ(13)  = M_J_DQ<12>
  VSS(40)  = GND
  DQ(9)  = M_J_DQ<8>
  VSS(39)  = GND
  DQS1N  = M_J_DQS_DN<1>
  DQS1P  = M_J_DQS_DP<1>
  VSS(38)  = GND
  DQ(15)  = M_J_DQ<14>
  VSS(37)  = GND
  DQ(11)  = M_J_DQ<10>
  VSS(36)  = GND
  DQ(21)  = M_J_DQ<20>
  VSS(35)  = GND
  DQ(17)  = M_J_DQ<16>
  VSS(34)  = GND
  DQS2N  = M_J_DQS_DN<2>
  DQS2P  = M_J_DQS_DP<2>
  VSS(33)  = GND
  DQ(23)  = M_J_DQ<22>
  VSS(32)  = GND
  DQ(19)  = M_J_DQ<18>
  VSS(31)  = GND
  DQ(29)  = M_J_DQ<28>
  VSS(30)  = GND
  DQ(25)  = M_J_DQ<24>
  VSS(29)  = GND
  DQS3N  = M_J_DQS_DN<3>
  DQS3P  = M_J_DQS_DP<3>
  VSS(28)  = GND
  DQ(31)  = M_J_DQ<30>
  VSS(27)  = GND
  DQ(27)  = M_J_DQ<26>
  VSS(26)  = GND
  CB(5)  = M_J_ECC<4>
  VSS(25)  = GND
  CB(1)  = M_J_ECC<0>
  VSS(24)  = GND
  DQS8N  = M_J_DQS_DN<8>
  DQS8P  = M_J_DQS_DP<8>
  VSS(23)  = GND
  CB(7)  = M_J_ECC<6>
  VSS(22)  = GND
  CB(3)  = M_J_ECC<2>
  VSS(21)  = GND
  CKE(1)  = M_J_CKE<1>
  VDD(12)  = PVDDQ_GHJ
  RFU(0)  = TP_CH_J_DIMM_J0_RFU_0
  VDD(11)  = PVDDQ_GHJ
  BG(1)  = M_J_BG<1>
  ALERT_N  = M_J_ALERT_N
  VDD(10)  = PVDDQ_GHJ
  A11  = M_J_MA<11>
  A7  = M_J_MA<7>
  VDD(9)  = PVDDQ_GHJ
  A5  = M_J_MA<5>
  A4  = M_J_MA<4>
  VDD(8)  = PVDDQ_GHJ
  A2  = M_J_MA<2>
  VDD(7)  = PVDDQ_GHJ
  CK1P  = M_J_CLK_DP<1>
  CK1N  = M_J_CLK_DN<1>
  VDD(6)  = PVDDQ_GHJ
  VTT(0)  = PVTT_GHJ
  PAR  = M_J_PAR
  VDD(5)  = PVDDQ_GHJ
  BA(1)  = M_J_BA<1>
  A10  = M_J_MA<10>
  VDD(4)  = PVDDQ_GHJ
  RFU(1)  = TP_CH_J_DIMM_J0_RFU_1
  A14_WE_N  = M_J_MA<14>
  VDD(3)  = PVDDQ_GHJ
  SAVE_N_NC  = FM_ADR_COMPLETE_GHJ_N
  VDD(2)  = PVDDQ_GHJ
  A13  = M_J_MA<13>
  VDD(1)  = PVDDQ_GHJ
  A17  = M_J_MA<17>
  C(2)  = M_J_C<2>
  VDD(0)  = PVDDQ_GHJ
  S3_N_C(1)  = M_J_CS_N<3>
  SA(2)  = PVPP_GHJ
  VSS(20)  = GND
  DQ(37)  = M_J_DQ<36>
  VSS(19)  = GND
  DQ(33)  = M_J_DQ<32>
  VSS(18)  = GND
  DQS4N  = M_J_DQS_DN<4>
  DQS4P  = M_J_DQS_DP<4>
  VSS(17)  = GND
  DQ(39)  = M_J_DQ<38>
  VSS(16)  = GND
  DQ(35)  = M_J_DQ<34>
  VSS(15)  = GND
  DQ(45)  = M_J_DQ<44>
  VSS(14)  = GND
  DQ(41)  = M_J_DQ<40>
  VSS(13)  = GND
  DQS5N  = M_J_DQS_DN<5>
  DQS5P  = M_J_DQS_DP<5>
  VSS(12)  = GND
  DQ(47)  = M_J_DQ<46>
  VSS(11)  = GND
  DQ(43)  = M_J_DQ<42>
  VSS(10)  = GND
  DQ(53)  = M_J_DQ<52>
  VSS(9)  = GND
  DQ(49)  = M_J_DQ<48>
  VSS(8)  = GND
  DQS6N  = M_J_DQS_DN<6>
  DQS6P  = M_J_DQS_DP<6>
  VSS(7)  = GND
  DQ(55)  = M_J_DQ<54>
  VSS(6)  = GND
  DQ(51)  = M_J_DQ<50>
  VSS(5)  = GND
  DQ(61)  = M_J_DQ<60>
  VSS(4)  = GND
  DQ(57)  = M_J_DQ<56>
  VSS(3)  = GND
  DQS7N  = M_J_DQS_DN<7>
  DQS7P  = M_J_DQS_DP<7>
  VSS(2)  = GND
  DQ(63)  = M_J_DQ<62>
  VSS(1)  = GND
  DQ(59)  = M_J_DQ<58>
  VSS(0)  = GND
  VDDSPD  = PVPP_GHJ
  SDA  = SMB_DDR_GHJ_VPP_SDA
  VPP(1)  = PVPP_GHJ
  VPP(0)  = PVPP_GHJ
  VPP(2)  = PVPP_GHJ

(kicad_pcb
	(version 20260206)
	(generator "pcbnew")
	(generator_version "10.0")
	(general
		(thickness 1.6)
		(legacy_teardrops no)
	)
	(paper "A4")
	(title_block
		(title "Wiwynn_Tioga_Pass_MB.brd")
		(comment 1 "Tioga Pass / footprint 437 of 4770 (J1G3), pads 52-101 of 291")
	)
	(layers
		(0 "F.Cu" signal "TOP")
		(4 "In1.Cu" signal "L2GND")
		(6 "In2.Cu" signal "L3")
		(8 "In3.Cu" signal "L4GND")
		(10 "In4.Cu" signal "L5")
		(12 "In5.Cu" signal "L6GND")
		(14 "In6.Cu" signal "L7VCC")
		(16 "In7.Cu" signal "L8VCC")
		(18 "In8.Cu" signal "L9GND")
		(20 "In9.Cu" signal "L10")
		(22 "In10.Cu" signal "L11GND")
		(24 "In11.Cu" signal "L12")
		(26 "In12.Cu" signal "L13GND")
		(2 "B.Cu" signal "BOTTOM")
		(9 "F.Adhes" user "F.Adhesive")
		(11 "B.Adhes" user "B.Adhesive")
		(13 "F.Paste" user "Package Geometry/Pastemask Top")
		(15 "B.Paste" user "Package Geometry/Pastemask Bottom")
		(5 "F.SilkS" user "Ref Des/Silkscreen Top")
		(7 "B.SilkS" user "Ref Des/Silkscreen Bottom")
		(1 "F.Mask" user "Board Geometry/Soldermask Top")
		(3 "B.Mask" user "Board Geometry/Soldermask Bottom")
		(17 "Dwgs.User" user "User.Drawings")
		(19 "Cmts.User" user "User.Comments")
		(21 "Eco1.User" user "User.Eco1")
		(23 "Eco2.User" user "User.Eco2")
		(25 "Edge.Cuts" user "Board Geometry/Outline")
		(27 "Margin" user)
		(31 "F.CrtYd" user "Package Geometry/Place Bound Top")
		(29 "B.CrtYd" user "Package Geometry/Place Bound Bottom")
		(35 "F.Fab" user "Ref Des/Assembly Top")
		(33 "B.Fab" user "Ref Des/Assembly Bottom")
	)
	(footprint ""
		(layer "F.Cu")
		(at 29.699458 3.778758 90)
		(property "Reference" "J1G3"
			(at 7.054088 34.562542 0)
			(unlocked yes)
			(layer "F.SilkS")
			(effects
				(font
					(size 0.7874 0.5842)
					(thickness 0.1524)
				)
				(justify left)
			)
		)
		(property "Value" ""
			(at 0 0 90)
			(layer "F.Fab")
			(effects
				(font
					(size 1.27 1.27)
				)
			)
		)
		(duplicate_pad_numbers_are_jumpers no)
		(pad "49" smd rect
			(at 0 40.80002 90)
			(size 1.8034 0.508)
			(layers "F.Cu" "F.Mask" "F.Paste")
			(net "M_J_ECC<1>")
		)
		(pad "50" smd rect
			(at 0 41.649904 90)
			(size 1.8034 0.508)
			(layers "F.Cu" "F.Mask" "F.Paste")
			(net "GND")
		)
		(pad "51" smd rect
			(at 0 42.500042 90)
			(size 1.8034 0.508)
			(layers "F.Cu" "F.Mask" "F.Paste")
			(net "M_J_DQS_DP<17>")
		)
		(pad "52" smd rect
			(at 0 43.349926 90)
			(size 1.8034 0.508)
			(layers "F.Cu" "F.Mask" "F.Paste")
			(net "M_J_DQS_DN<17>")
		)
		(pad "53" smd rect
			(at 0 44.200064 90)
			(size 1.8034 0.508)
			(layers "F.Cu" "F.Mask" "F.Paste")
			(net "GND")
		)
		(pad "54" smd rect
			(at 0 45.049948 90)
			(size 1.8034 0.508)
			(layers "F.Cu" "F.Mask" "F.Paste")
			(net "M_J_ECC<7>")
		)
		(pad "55" smd rect
			(at 0 45.900086 90)
			(size 1.8034 0.508)
			(layers "F.Cu" "F.Mask" "F.Paste")
			(net "GND")
		)
		(pad "56" smd rect
			(at 0 46.74997 90)
			(size 1.8034 0.508)
			(layers "F.Cu" "F.Mask" "F.Paste")
			(net "M_J_ECC<3>")
		)
		(pad "57" smd rect
			(at 0 47.600108 90)
			(size 1.8034 0.508)
			(layers "F.Cu" "F.Mask" "F.Paste")
			(net "GND")
		)
		(pad "58" smd rect
			(at 0 48.449992 90)
			(size 1.8034 0.508)
			(layers "F.Cu" "F.Mask" "F.Paste")
			(net "M_GHJ_RST_N")
		)
		(pad "59" smd rect
			(at 0 49.299876 90)
			(size 1.8034 0.508)
			(layers "F.Cu" "F.Mask" "F.Paste")
			(net "PVDDQ_GHJ")
		)
		(pad "60" smd rect
			(at 0 50.150014 90)
			(size 1.8034 0.508)
			(layers "F.Cu" "F.Mask" "F.Paste")
			(net "M_J_CKE<0>")
		)
		(pad "61" smd rect
			(at 0 50.999898 90)
			(size 1.8034 0.508)
			(layers "F.Cu" "F.Mask" "F.Paste")
			(net "PVDDQ_GHJ")
		)
		(pad "62" smd rect
			(at 0 51.850036 90)
			(size 1.8034 0.508)
			(layers "F.Cu" "F.Mask" "F.Paste")
			(net "M_J_ACT_N")
		)
		(pad "63" smd rect
			(at 0 52.69992 90)
			(size 1.8034 0.508)
			(layers "F.Cu" "F.Mask" "F.Paste")
			(net "M_J_BG<0>")
		)
		(pad "64" smd rect
			(at 0 53.550058 90)
			(size 1.8034 0.508)
			(layers "F.Cu" "F.Mask" "F.Paste")
			(net "PVDDQ_GHJ")
		)
		(pad "65" smd rect
			(at 0 54.399942 90)
			(size 1.8034 0.508)
			(layers "F.Cu" "F.Mask" "F.Paste")
			(net "M_J_MA<12>")
		)
		(pad "66" smd rect
			(at 0 55.25008 90)
			(size 1.8034 0.508)
			(layers "F.Cu" "F.Mask" "F.Paste")
			(net "M_J_MA<9>")
		)
		(pad "67" smd rect
			(at 0 56.099964 90)
			(size 1.8034 0.508)
			(layers "F.Cu" "F.Mask" "F.Paste")
			(net "PVDDQ_GHJ")
		)
		(pad "68" smd rect
			(at 0 56.950102 90)
			(size 1.8034 0.508)
			(layers "F.Cu" "F.Mask" "F.Paste")
			(net "M_J_MA<8>")
		)
		(pad "69" smd rect
			(at 0 57.799986 90)
			(size 1.8034 0.508)
			(layers "F.Cu" "F.Mask" "F.Paste")
			(net "M_J_MA<6>")
		)
		(pad "70" smd rect
			(at 0 58.650124 90)
			(size 1.8034 0.508)
			(layers "F.Cu" "F.Mask" "F.Paste")
			(net "PVDDQ_GHJ")
		)
		(pad "71" smd rect
			(at 0 59.500008 90)
			(size 1.8034 0.508)
			(layers "F.Cu" "F.Mask" "F.Paste")
			(net "M_J_MA<3>")
		)
		(pad "72" smd rect
			(at 0 60.349892 90)
			(size 1.8034 0.508)
			(layers "F.Cu" "F.Mask" "F.Paste")
			(net "M_J_MA<1>")
		)
		(pad "73" smd rect
			(at 0 61.20003 90)
			(size 1.8034 0.508)
			(layers "F.Cu" "F.Mask" "F.Paste")
			(net "PVDDQ_GHJ")
		)
		(pad "74" smd rect
			(at 0 62.049914 90)
			(size 1.8034 0.508)
			(layers "F.Cu" "F.Mask" "F.Paste")
			(net "M_J_CLK_DP<0>")
		)
		(pad "75" smd rect
			(at 0 62.900052 90)
			(size 1.8034 0.508)
			(layers "F.Cu" "F.Mask" "F.Paste")
			(net "M_J_CLK_DN<0>")
		)
		(pad "76" smd rect
			(at 0 63.749936 90)
			(size 1.8034 0.508)
			(layers "F.Cu" "F.Mask" "F.Paste")
			(net "PVDDQ_GHJ")
		)
		(pad "77" smd rect
			(at 0 64.600074 90)
			(size 1.8034 0.508)
			(layers "F.Cu" "F.Mask" "F.Paste")
			(net "PVTT_GHJ")
		)
		(pad "78" smd rect
			(at 0 70.550024 90)
			(size 1.8034 0.508)
			(layers "F.Cu" "F.Mask" "F.Paste")
			(net "FM_DIMM_EVENT_COD_N")
		)
		(pad "79" smd rect
			(at 0 71.399908 90)
			(size 1.8034 0.508)
			(layers "F.Cu" "F.Mask" "F.Paste")
			(net "M_J_MA<0>")
		)
		(pad "80" smd rect
			(at 0 72.250046 90)
			(size 1.8034 0.508)
			(layers "F.Cu" "F.Mask" "F.Paste")
			(net "PVDDQ_GHJ")
		)
		(pad "81" smd rect
			(at 0 73.09993 90)
			(size 1.8034 0.508)
			(layers "F.Cu" "F.Mask" "F.Paste")
			(net "M_J_BA<0>")
		)
		(pad "82" smd rect
			(at 0 73.950068 90)
			(size 1.8034 0.508)
			(layers "F.Cu" "F.Mask" "F.Paste")
			(net "M_J_MA<16>")
		)
		(pad "83" smd rect
			(at 0 74.799952 90)
			(size 1.8034 0.508)
			(layers "F.Cu" "F.Mask" "F.Paste")
			(net "PVDDQ_GHJ")
		)
		(pad "84" smd rect
			(at 0 75.65009 90)
			(size 1.8034 0.508)
			(layers "F.Cu" "F.Mask" "F.Paste")
			(net "M_J_CS_N<0>")
		)
		(pad "85" smd rect
			(at 0 76.499974 90)
			(size 1.8034 0.508)
			(layers "F.Cu" "F.Mask" "F.Paste")
			(net "PVDDQ_GHJ")
		)
		(pad "86" smd rect
			(at 0 77.350112 90)
			(size 1.8034 0.508)
			(layers "F.Cu" "F.Mask" "F.Paste")
			(net "M_J_MA<15>")
		)
		(pad "87" smd rect
			(at 0 78.199996 90)
			(size 1.8034 0.508)
			(layers "F.Cu" "F.Mask" "F.Paste")
			(net "M_J_ODT<0>")
		)
		(pad "88" smd rect
			(at 0 79.04988 90)
			(size 1.8034 0.508)
			(layers "F.Cu" "F.Mask" "F.Paste")
			(net "PVDDQ_GHJ")
		)
		(pad "89" smd rect
			(at 0 79.900018 90)
			(size 1.8034 0.508)
			(layers "F.Cu" "F.Mask" "F.Paste")
			(net "M_J_CS_N<1>")
		)
		(pad "90" smd rect
			(at 0 80.749902 90)
			(size 1.8034 0.508)
			(layers "F.Cu" "F.Mask" "F.Paste")
			(net "PVDDQ_GHJ")
		)
		(pad "91" smd rect
			(at 0 81.60004 90)
			(size 1.8034 0.508)
			(layers "F.Cu" "F.Mask" "F.Paste")
			(net "M_J_ODT<1>")
		)
		(pad "92" smd rect
			(at 0 82.449924 90)
			(size 1.8034 0.508)
			(layers "F.Cu" "F.Mask" "F.Paste")
			(net "PVDDQ_GHJ")
		)
		(pad "93" smd rect
			(at 0 83.300062 90)
			(size 1.8034 0.508)
			(layers "F.Cu" "F.Mask" "F.Paste")
			(net "M_J_CS_N<2>")
		)
		(pad "94" smd rect
			(at 0 84.149946 90)
			(size 1.8034 0.508)
			(layers "F.Cu" "F.Mask" "F.Paste")
			(net "GND")
		)
		(pad "95" smd rect
			(at 0 85.000084 90)
			(size 1.8034 0.508)
			(layers "F.Cu" "F.Mask" "F.Paste")
			(net "M_J_DQ<37>")
		)
		(pad "96" smd rect
			(at 0 85.849968 90)
			(size 1.8034 0.508)
			(layers "F.Cu" "F.Mask" "F.Paste")
			(net "GND")
		)
		(pad "97" smd rect
			(at 0 86.700106 90)
			(size 1.8034 0.508)
			(layers "F.Cu" "F.Mask" "F.Paste")
			(net "M_J_DQ<33>")
		)
		(pad "98" smd rect
			(at 0 87.54999 90)
			(size 1.8034 0.508)
			(layers "F.Cu" "F.Mask" "F.Paste")
			(net "GND")
		)
	)
)
